# S9S_MB_2U (Grand Teton) — schematic parts with pin connectivity, parts 5880–5880 of 6093; source: Cadence DE-HDL packaged netlist (pstxprt.dat, pstxnet.dat, pstchip.dat)

U2  SOCKET4677_AZIF0045P001C01CS  SOCKET4677_AZIF0045-P001C01CS IO  pkg SOCKET4677_82X64-5XA_H466  page 13  (pins 653-978 of 4677)
  AP85  PE4_TX_DN11  OUT  = P5E_CPU0_PE4_TX_DN<11>
  AP87  VSS280  POWER  = GND
  AP89  PE4_RX_DN11  IN  = P5E_CPU0_PE4_RX_DN<11>
  AP91  VSS281  POWER  = GND
  AR1  VSS282  POWER  = GND
  AR3  UPI0_TX_DP13  OUT  = UPI_CPU0_CPU1_P0P1_DN<13>
  AR5  VSS294  POWER  = GND
  AR7  UPI0_RX_DP12  IN  = UPI_CPU1_CPU0_P1P0_DN<12>
  AR9  VSS308  POWER  = GND
  AR11  PE0_RX_DP12  IN  = P5E_CPU0_PE0_RX_DP<12>
  AR13  VSS283  POWER  = GND
  AR15  PE0_TX_DP11  OUT  = P5E_CPU0_PE0_TX_DP<11>
  AR17  RSVD3  BI  = NC_CPU0_UPI0_APROBE<1>
  AR19  VSS284  POWER  = GND
  AR21  DDR3_SB_DQS_DP8  BI  = M_D_CPU0_SB_DQS_DP<8>
  AR23  VSS285  POWER  = GND
  AR25  VSS286  POWER  = GND
  AR27  DDR3_SB_DQS_DP6  BI  = M_D_CPU0_SB_DQS_DP<6>
  AR29  VSS287  POWER  = GND
  AR31  VSS288  POWER  = GND
  AR33  DDR3_SB_DQS_DP5  BI  = M_D_CPU0_SB_DQS_DP<5>
  AR35  VSS289  POWER  = GND
  AR37  VSS290  POWER  = GND
  AR39  DDR3_SB_DQS_DN4  BI  = M_D_CPU0_SB_DQS_DN<4>
  AR41  VSS291  POWER  = GND
  AR43  VSS292  POWER  = GND
  AR45  DDR3_CLK_DP1  OUT  = M_D_CPU0_CLK_DP<1>
  AR48  VSS293  POWER  = GND
  AR50  VSS295  POWER  = GND
  AR52  DDR3_SA_CA1  OUT  = M_D_CPU0_SA_CA<1>
  AR54  VSS296  POWER  = GND
  AR56  VSS297  POWER  = GND
  AR58  DDR3_SA_DQS_DP9  BI  = M_D_CPU0_SA_DQS_DP<9>
  AR60  VSS298  POWER  = GND
  AR62  VSS299  POWER  = GND
  AR64  DDR3_SA_DQS_DP8  BI  = M_D_CPU0_SA_DQS_DP<8>
  AR66  VSS300  POWER  = GND
  AR68  VSS301  POWER  = GND
  AR70  DDR3_SA_DQS_DP7  BI  = M_D_CPU0_SA_DQS_DP<7>
  AR72  VSS302  POWER  = GND
  AR74  VSS303  POWER  = GND
  AR76  DDR3_SA_DQS_DP6  BI  = M_D_CPU0_SA_DQS_DP<6>
  AR78  VSS304  POWER  = GND
  AR80  UPI2_TX_DN14  OUT  = UPI_CPU0_CPU1_P2P2_DN<9>
  AR82  VSS305  POWER  = GND
  AR84  VSS306  POWER  = GND
  AR86  PE4_TX_DN12  OUT  = P5E_CPU0_PE4_TX_DN<12>
  AR88  VSS307  POWER  = GND
  AR90  PE4_RX_DP12  IN  = P5E_CPU0_PE4_RX_DP<12>
  AT2  UPI0_TX_DN13  OUT  = UPI_CPU0_CPU1_P0P1_DP<13>
  AT4  VSS318  POWER  = GND
  AT6  UPI0_RX_DP13  IN  = UPI_CPU1_CPU0_P1P0_DN<13>
  AT8  VSS332  POWER  = GND
  AT10  PE0_RX_DP13  IN  = P5E_CPU0_PE0_RX_DP<13>
  AT12  VSS309  POWER  = GND
  AT14  PE0_TX_DP12  OUT  = P5E_CPU0_PE0_TX_DP<12>
  AT16  VSS310  POWER  = GND
  AT18  BIST_ENABLE  IN  = PD_CPU0_BIST_ENABLE
  AT20  VSS311  POWER  = GND
  AT22  VSS312  POWER  = GND
  AT24  RSVD4  BI  = NC_CPU0_VIEWPIN_DIE00<1>
  AT26  VSS313  POWER  = GND
  AT28  VSS314  POWER  = GND
  AT30  BCLK0_DN  IN  = CLK_100M_DB2000_CPU0_BCLK0_DN
  AT32  VSS315  POWER  = GND
  AT34  VSS316  POWER  = GND
  AT36  VCCD_HV0  POWER  = PVCCD_HV_CPU0
  AT38  VSS317  POWER  = GND
  AT40  VSS319  POWER  = GND
  AT42  DDR0_A_RSP0  IN  = M_A_CPU0_SA_RSP<0>
  AT44  VSS320  POWER  = GND
  AT47  DDR2_ALERT_N  IN  = M_C_CPU0_ALERT_N
  AT49  DDR0_ALERT_N  IN  = M_A_CPU0_ALERT_N
  AT51  VSS321  POWER  = GND
  AT53  VSS322  POWER  = GND
  AT55  VCCD_HV1  POWER  = PVCCD_HV_CPU0
  AT57  VSS323  POWER  = GND
  AT59  VSS324  POWER  = GND
  AT61  VCCFA_EHV4  POWER  = PVCCFA_EHV_CPU0
  AT63  VSS325  POWER  = GND
  AT65  VSS326  POWER  = GND
  AT67  RSVD5  BI  = NC_CPU0_UPI2_APROBE<1>
  AT69  VSS327  POWER  = GND
  AT71  VSS328  POWER  = GND
  AT73  VCCFA_EHV_FIVRA22  POWER  = PVCCFA_EHV_FIVRA_CPU0
  AT75  VSS329  POWER  = GND
  AT77  VSS330  POWER  = GND
  AT79  VSS331  POWER  = GND
  AT81  UPI2_TX_DP14  OUT  = UPI_CPU0_CPU1_P2P2_DP<9>
  AT83  UPI2_TX_DN15  OUT  = UPI_CPU0_CPU1_P2P2_DN<8>
  AT85  VSS_VCCFA_EHV_FIVRA_SENSE  POWER  = VSENSE_PVCCFA_EHV_FIVRA_CPU0_DN
  AT87  PE4_TX_DP12  OUT  = P5E_CPU0_PE4_TX_DP<12>
  AT89  VCCFA_EHV_FIVRA23  POWER  = PVCCFA_EHV_FIVRA_CPU0
  AT91  PE4_RX_DN12  IN  = P5E_CPU0_PE4_RX_DN<12>
  AU1  UPI0_TX_DN14  OUT  = UPI_CPU0_CPU1_P0P1_DN<14>
  AU3  VCCD_HV2  POWER  = PVCCD_HV_CPU0
  AU5  UPI0_RX_DN13  IN  = UPI_CPU1_CPU0_P1P0_DP<13>
  AU7  VCCD_HV5  POWER  = PVCCD_HV_CPU0
  AU9  PE0_RX_DN13  IN  = P5E_CPU0_PE0_RX_DN<13>
  AU11  VCCFA_EHV_SENSE  POWER  = VSENSE_PVCCFA_EHV_CPU0_DP
  AU13  PE0_TX_DN12  OUT  = P5E_CPU0_PE0_TX_DN<12>
  AU15  VCCFA_EHV_FIVRA24  POWER  = PVCCFA_EHV_FIVRA_CPU0
  AU17  FRMAGENT  IN  = PU_CPU0_FRMAGENT
  AU19  PROCHOT_N  IN  = H_CPU0_PROCHOT_LVC1_N
  AU21  MEMHOT_IN_N  IN  = H_CPU0_MEMHOT_IN_LVC1_N
  AU23  SAFE_MODE_BOOT  BI  = PU_CPU0_SAFE_MODE_BOOT
  AU25  RSVD6  BI  = NC_CPU0_VIEWPIN_DIE00<2>
  AU27  VSS333  POWER  = GND
  AU29  BCLK2_DN  IN  = CLK_100M_DB2000_CPU0_BCLK2_DN
  AU31  VSS334  POWER  = GND
  AU33  RSVD7  BI  = NC_CPU0_DDR23_VIEWDIG1
  AU35  VCCD_HV3  POWER  = PVCCD_HV_CPU0
  AU37  VSS335  POWER  = GND
  AU39  VSS336  POWER  = GND
  AU41  VSS337  POWER  = GND
  AU43  DDR0_A_RSP1  IN  = M_A_CPU0_SA_RSP<1>
  AU45  VSS338  POWER  = GND
  AU48  VSS339  POWER  = GND
  AU50  DDR01_RESET_N  OUT  = RST_CPU0_DRAM_AB_N
  AU52  RSVD8  BI  = TP_CPU0_SPARE5
  AU54  VCCD_HV4  POWER  = PVCCD_HV_CPU0
  AU56  RSVD9  BI  = NC_CPU0_DDR01_VIEWDIG1
  AU58  RSVD10  BI  = NC_CPU0_DDR01_VIEWDIG0
  AU60  VCCFA_EHV5  POWER  = PVCCFA_EHV_CPU0
  AU62  RSVD11  BI  = TP_SPI_IBL_CPU0_TPM_CLK
  AU64  RSVD12  BI  = TP_ESPI_IBL_CPU0_IO2_LVC1
  AU66  RSVD13  BI  = NC_CPU0_PE4_APROBE<1>
  AU68  RSVD14  BI  = NC_CPU0_UPI2_APROBE<0>
  AU70  VSS340  POWER  = GND
  AU72  VSS341  POWER  = GND
  AU74  VSS342  POWER  = GND
  AU76  VSS343  POWER  = GND
  AU78  UPI2_TX_DN11  OUT  = UPI_CPU0_CPU1_P2P2_DN<12>
  AU80  VSS344  POWER  = GND
  AU82  UPI2_TX_DP16  OUT  = UPI_CPU0_CPU1_P2P2_DP<7>
  AU84  VSS345  POWER  = GND
  AU86  PE4_TX_DN13  OUT  = P5E_CPU0_PE4_TX_DN<13>
  AU88  VSS346  POWER  = GND
  AU90  PE4_RX_DP13  IN  = P5E_CPU0_PE4_RX_DP<13>
  AV2  UPI0_TX_DP14  OUT  = UPI_CPU0_CPU1_P0P1_DP<14>
  AV4  VSS349  POWER  = GND
  AV6  UPI0_RX_DN14  IN  = UPI_CPU1_CPU0_P1P0_DP<14>
  AV8  VSS351  POWER  = GND
  AV10  PE0_RX_DN14  IN  = P5E_CPU0_PE0_RX_DN<14>
  AV12  VSS347  POWER  = GND
  AV14  PE0_TX_DN13  OUT  = P5E_CPU0_PE0_TX_DN<13>
  AV16  VSS348  POWER  = GND
  AV18  NMI  IN  = H_CPU0_NMI_LVC1_N
  AV20  PWRGOOD  IN  = PWRGD_CPU0_LVC1
  AV22  PREQ_N  IN  = H_CPU0_PREQ_QS_GTL_R_N
  AV24  MEMTRIP_N  OUT  = H_CPU0_MEMTRIP_LVC1_R_N
  AV26  RSVD15  BI  = NC_CPU0_VIEWPIN_DIE00<3>
  AV28  BCLK2_DP  IN  = CLK_100M_DB2000_CPU0_BCLK2_DP
  AV30  BCLK0_DP  IN  = CLK_100M_DB2000_CPU0_BCLK0_DP
  AV32  RSVD16  BI  = NC_CPU0_DDR23_VIEWDIG0
  AV34  VCCD_HV6  POWER  = PVCCD_HV_CPU0
  AV36  VCCD_HV7  POWER  = PVCCD_HV_CPU0
  AV38  RSVD17  BI  = NC_CPU0_THERMADC
  AV40  RSVD18  BI  = NC_CPU0_THERMADA
  AV42  DDR0_B_RSP1  IN  = M_A_CPU0_SB_RSP<1>
  AV44  DDR0_B_RSP0  IN  = M_A_CPU0_SB_RSP<0>
  AV47  DDR3_ALERT_N  IN  = M_D_CPU0_ALERT_N
  AV49  DDR1_ALERT_N  IN  = M_B_CPU0_ALERT_N
  AV51  DDR23_RESET_N  OUT  = RST_CPU0_DRAM_CD_N
  AV53  VCCD_HV8  POWER  = PVCCD_HV_CPU0
  AV55  VCCD_HV9  POWER  = PVCCD_HV_CPU0
  AV57  FBRK_N  IN  = FM_CPU_FBRK_DEBUG_R_N
  AV59  RSVD19  BI  = TP_EV_CPU0_EXT_BGREF
  AV61  VCCFA_EHV6  POWER  = PVCCFA_EHV_CPU0
  AV63  RSVD20  BI  = TP_SPI_S3M_CPU0_CS1_LVC1_R_N
  AV65  RSVD21  BI  = NC_CPU0_MDFI_DIE01_EW0
  AV67  RSVD22  BI  = NC_CPU0_PE4_APROBE<0>
  AV69  TEST_7  BI  = FM_S3M_CPU0_LVC1_GPIO_2
  AV71  PARTITION_ID1  IN  = FM_S3M_CPU0_LVC1_GPIO_1
  AV73  UPI2_RX_DN13  IN  = UPI_CPU1_CPU0_P2P2_DN<10>
  AV75  UPI2_RX_DP16  IN  = UPI_CPU1_CPU0_P2P2_DN<7>
  AV77  VSS350  POWER  = GND
  AV79  UPI2_TX_DP11  OUT  = UPI_CPU0_CPU1_P2P2_DP<12>
  AV81  UPI2_TX_DN16  OUT  = UPI_CPU0_CPU1_P2P2_DN<7>
  AV83  UPI2_TX_DP15  OUT  = UPI_CPU0_CPU1_P2P2_DP<8>
  AV85  PE4_TX_DP13  OUT  = P5E_CPU0_PE4_TX_DP<13>
  AV87  VSS352  POWER  = GND
  AV89  PE4_RX_DN13  IN  = P5E_CPU0_PE4_RX_DN<13>
  AV91  VSS353  POWER  = GND
  AW1  VSS354  POWER  = GND
  AW3  UPI0_TX_DP15  OUT  = UPI_CPU0_CPU1_P0P1_DN<15>
  AW5  VSS359  POWER  = GND
  AW7  UPI0_RX_DP14  IN  = UPI_CPU1_CPU0_P1P0_DN<14>
  AW9  VSS368  POWER  = GND
  AW11  PE0_RX_DP14  IN  = P5E_CPU0_PE0_RX_DP<14>
  AW13  VSS355  POWER  = GND
  AW15  PE0_TX_DP13  OUT  = P5E_CPU0_PE0_TX_DP<13>
  AW17  DMIMODE_OVERRIDE  IN  = PD_CPU0_DMIMODE_OVERRIDE
  AW19  RSVD23  BI  = TP_FM_IBL_WAKE_CPU0_N
  AW21  VSS356  POWER  = GND
  AW23  VSS357  POWER  = GND
  AW25  VSS358  POWER  = GND
  AW60  VCCFA_EHV7  POWER  = PVCCFA_EHV_CPU0
  AW62  VSS360  POWER  = GND
  AW64  RSVD24  BI  = TP_SPI_S3M_CPU0_IO1_LVC1_R
  AW66  VSS361  POWER  = GND
  AW68  VSS362  POWER  = GND
  AW70  RSVD25  BI  = FM_S3M_CPU0_LVC1_GPIO_4
  AW72  VSS363  POWER  = GND
  AW74  UPI2_RX_DN16  IN  = UPI_CPU1_CPU0_P2P2_DP<7>
  AW76  VCCFA_EHV_FIVRA25  POWER  = PVCCFA_EHV_FIVRA_CPU0
  AW78  UPI2_TX_DN10  OUT  = UPI_CPU0_CPU1_P2P2_DN<13>
  AW80  VSS364  POWER  = GND
  AW82  VSS365  POWER  = GND
  AW84  VSS366  POWER  = GND
  AW86  PE4_TX_DN14  OUT  = P5E_CPU0_PE4_TX_DN<14>
  AW88  VSS367  POWER  = GND
  AW90  PE4_RX_DP14  IN  = P5E_CPU0_PE4_RX_DP<14>
  AY2  UPI0_TX_DN15  OUT  = UPI_CPU0_CPU1_P0P1_DP<15>
  AY4  VSS371  POWER  = GND
  AY6  UPI0_RX_DP15  IN  = UPI_CPU1_CPU0_P1P0_DN<15>
  AY8  VSS375  POWER  = GND
  AY10  PE0_RX_DP15  IN  = P5E_CPU0_PE0_RX_DP<15>
  AY12  VSS369  POWER  = GND
  AY14  PE0_TX_DP14  OUT  = P5E_CPU0_PE0_TX_DP<14>
  AY16  VSS370  POWER  = GND
  AY18  VCCINFAON33  POWER  = PVCCINFAON_CPU0
  AY20  TAP_ODT_EN  IN  = PU_TAP_ODT_CPU0_EN
  AY22  ERROR_N1  OUT  = H_CPU0_ERR1_LVC1_R_N
  AY24  RSVD26  BI  = NC_CPU0_SOC_SPARE0
  AY26  RSVD27  BI  = NC_CPU0_VIEWPIN_DIE00<0>
  AY61  RSVD28  BI  = TP_SPI_IBL_CPU0_TPM_IO1
  AY63  PKG_ID1  IN  = FM_CPU0_PKGID1
  AY65  RSVD29  BI  = NC_CPU0_VIEWPIN_DIE01<2>
  AY67  RSVD30  BI  = TP_SPI_IBL_CPU0_TPM_CS0_N
  AY69  TEST_8  BI  = FM_S3M_CPU0_LVC1_GPIO_3
  AY71  VSS372  POWER  = GND
  AY73  UPI2_RX_DP13  IN  = UPI_CPU1_CPU0_P2P2_DP<10>
  AY75  UPI2_RX_DN14  IN  = UPI_CPU1_CPU0_P2P2_DN<9>
  AY77  VSS373  POWER  = GND
  AY79  VSS374  POWER  = GND
  AY81  VSS376  POWER  = GND
  AY83  VSS377  POWER  = GND
  AY85  VCCFA_EHV_FIVRA_SENSE  POWER  = VSENSE_PVCCFA_EHV_FIVRA_CPU0_DP
  AY87  PE4_TX_DP14  OUT  = P5E_CPU0_PE4_TX_DP<14>
  AY89  VCCFA_EHV_FIVRA26  POWER  = PVCCFA_EHV_FIVRA_CPU0
  AY91  PE4_RX_DN14  IN  = P5E_CPU0_PE4_RX_DN<14>
  B6  VSS387  POWER  = GND
  B8  DDR0_SB_DQ28  BI  = M_A_CPU0_SB_DQ<28>
  B10  DDR0_SB_DQ25  BI  = M_A_CPU0_SB_DQ<25>
  B12  VSS378  POWER  = GND
  B14  DDR1_SB_DQ30  BI  = M_B_CPU0_SB_DQ<30>
  B16  DDR1_SB_DQ25  BI  = M_B_CPU0_SB_DQ<25>
  B18  VSS379  POWER  = GND
  B20  DDR0_SB_DQ20  BI  = M_A_CPU0_SB_DQ<20>
  B22  DDR0_SB_DQ17  BI  = M_A_CPU0_SB_DQ<17>
  B24  VSS380  POWER  = GND
  B26  DDR0_SB_DQ12  BI  = M_A_CPU0_SB_DQ<12>
  B28  DDR0_SB_DQ9  BI  = M_A_CPU0_SB_DQ<9>
  B30  VSS381  POWER  = GND
  B32  DDR0_SB_ECC0  BI  = M_A_CPU0_SB_CB<0>
  B34  DDR0_SB_ECC5  BI  = M_A_CPU0_SB_CB<5>
  B36  VSS382  POWER  = GND
  B38  DDR0_SB_CS_N0  OUT  = M_A_CPU0_SB_CS_N<0>
  B40  DDR0_SB_CA4  OUT  = M_A_CPU0_SB_CA<4>
  B42  VSS384  POWER  = GND
  B44  DDR0_CLK_DN0  OUT  = M_A_CPU0_CLK_DN<0>
  B49  VSS385  POWER  = GND
  B51  DDR0_SA_CA2  OUT  = M_A_CPU0_SA_CA<2>
  B53  DDR0_SA_CS_N1  OUT  = M_A_CPU0_SA_CS_N<1>
  B55  VSS386  POWER  = GND
  B57  DDR0_SA_ECC4  BI  = M_A_CPU0_SA_CB<4>
  B59  DDR0_SA_ECC1  BI  = M_A_CPU0_SA_CB<1>
  B61  VSS388  POWER  = GND
  B63  DDR0_SA_DQ28  BI  = M_A_CPU0_SA_DQ<28>
  B65  DDR0_SA_DQ25  BI  = M_A_CPU0_SA_DQ<25>
  B67  VSS389  POWER  = GND
  B69  DDR0_SA_DQ20  BI  = M_A_CPU0_SA_DQ<20>
  B71  DDR0_SA_DQS_DN2  BI  = M_A_CPU0_SA_DQS_DN<2>
  B73  DDR0_SA_DQ16  BI  = M_A_CPU0_SA_DQ<16>
  B75  VSS390  POWER  = GND
  B77  DDR0_SA_DQS_DN0  BI  = M_A_CPU0_SA_DQS_DN<0>
  B79  DDR0_SA_DQ1  BI  = M_A_CPU0_SA_DQ<1>
  B81  DDR0_SA_DQ0  BI  = M_A_CPU0_SA_DQ<0>
  B83  VSS391  POWER  = GND
  B85  UPI2_TX_DN0  OUT  = UPI_CPU0_CPU1_P2P2_DN<23>
  B87  VSS392  POWER  = GND
  BA1  UPI0_TX_DP16  OUT  = UPI_CPU0_CPU1_P0P1_DP<16>
  BA3  VCCD_HV10  POWER  = PVCCD_HV_CPU0
  BA5  UPI0_RX_DN15  IN  = UPI_CPU1_CPU0_P1P0_DP<15>
  BA7  VCCD_HV11  POWER  = PVCCD_HV_CPU0
  BA9  PE0_RX_DN15  IN  = P5E_CPU0_PE0_RX_DN<15>
  BA11  VSS_VCCFA_EHV_SENSE  POWER  = VSENSE_PVCCFA_EHV_CPU0_DN
  BA13  PE0_TX_DN14  OUT  = P5E_CPU0_PE0_TX_DN<14>
  BA15  VCCINFAON34  POWER  = PVCCINFAON_CPU0
  BA17  VSS393  POWER  = GND
  BA19  VCCVNN0  POWER  = PVNN_MAIN_CPU0
  BA21  VCC_3P3_AUX1  POWER  = P3V3_AUX
  BA23  UPI0_AC_COUPLING  IN  = PU_CPU0_UPI0_AC_COUPLING
  BA25  RSVD31  BI  = NC_CPU0_SOC_SPARE4
  BA60  VSS394  POWER  = GND
  BA62  RSVD32  BI  = TP_SPI_S3M_CPU0_IO0_LVC1_R
  BA64  VSS395  POWER  = GND
  BA66  RSVD33  BI  = TP_SPI_IBL_CPU0_TPM_IO0
  BA68  RSVD34  BI  = TP_SPI_S3M_CPU0_OE_LVC1_R_N
  BA70  PARTITION_ID0  IN  = FM_S3M_CPU0_LVC1_GPIO_0
  BA72  UPI2_RX_DN12  IN  = UPI_CPU1_CPU0_P2P2_DP<11>
  BA74  VSS397  POWER  = GND
  BA76  UPI2_RX_DP14  IN  = UPI_CPU1_CPU0_P2P2_DP<9>
  BA78  UPI2_TX_DP10  OUT  = UPI_CPU0_CPU1_P2P2_DP<13>
  BA80  UPI2_TX_DN17  OUT  = UPI_CPU0_CPU1_P2P2_DN<6>
  BA82  UPI2_TX_DP18  OUT  = UPI_CPU0_CPU1_P2P2_DP<5>
  BA84  VSS398  POWER  = GND
  BA86  PE4_TX_DN15  OUT  = P5E_CPU0_PE4_TX_DN<15>
  BA88  VSS399  POWER  = GND
  BA90  PE4_RX_DP15  IN  = P5E_CPU0_PE4_RX_DP<15>
  BB2  UPI0_TX_DN16  OUT  = UPI_CPU0_CPU1_P0P1_DN<16>
  BB4  VSS407  POWER  = GND
  BB6  UPI0_RX_DN16  IN  = UPI_CPU1_CPU0_P1P0_DP<16>
  BB8  VSS413  POWER  = GND
  BB10  VSS400  POWER  = GND
  BB12  VSS401  POWER  = GND
  BB14  PE0_TX_DN15  OUT  = P5E_CPU0_PE0_TX_DN<15>
  BB16  VSS402  POWER  = GND
  BB18  DMI_RX_DN0  IN  = DMI_CPU0_PCH_RX_C_DN<0>
  BB20  VSS403  POWER  = GND
  BB22  VSS404  POWER  = GND
  BB24  VSS405  POWER  = GND
  BB26  VSS406  POWER  = GND
  BB61  RSVD35  BI  = TP_SPI_S3M_CPU0_CS0_LVC1_R_N
  BB63  VSS408  POWER  = GND
